# S9S_MB_2U (Grand Teton) — schematic netlist excerpt (pin names and nets, part order shuffled) for the footprints in the layout excerpt that follows; sources: Cadence DE-HDL packaged netlist, KiCad conversion of 03242023_DA0F0TMBIJ0_F0T_Motherboard_J_brd_V01_OCP.brd

R598  Q_RES  0 5% CHIP  pkg 0402LF  page 241 : A = I3C_SPD_DDRABCD_CPU1_BMC_R_SDA ; B = I3C_SPD_DDRABCD_CPU1_BMC_SDA
C168  Q_CAP_DIFFBUS  DIFF BUS_0.22UF 6.3V 20% X6S  pkg C0201  page 178 : \1\ = DMI_CPU0_PCH_RX_C_DP<1> ; \2\ = DMI_CPU0_PCH_RX_DP<1>
C2077  Q_CAP_DIFFBUS  DIFF BUS_0.22UF 6.3V 20% X6S  pkg C0201  page 181 : \1\ = P3E_PCH_BMC_TX_DP ; \2\ = P3E_PCH_BMC_TX_C_DP

(kicad_pcb
	(version 20260206)
	(generator "pcbnew")
	(generator_version "10.0")
	(general
		(thickness 1.6)
		(legacy_teardrops no)
	)
	(paper "A4")
	(title_block
		(title "03242023_DA0F0TMBIJ0_F0T_Motherboard_J_brd_V01_OCP.brd")
		(comment 1 "Grand Teton / footprints 4963-4965 of 6105")
	)
	(layers
		(0 "F.Cu" signal "TOP")
		(4 "In1.Cu" signal "GND")
		(6 "In2.Cu" signal "IN1")
		(8 "In3.Cu" signal "GND1")
		(10 "In4.Cu" signal "IN2")
		(12 "In5.Cu" signal "GND2")
		(14 "In6.Cu" signal "IN3")
		(16 "In7.Cu" signal "GND3")
		(18 "In8.Cu" signal "VCC")
		(20 "In9.Cu" signal "VCC1")
		(22 "In10.Cu" signal "GND4")
		(24 "In11.Cu" signal "IN4")
		(26 "In12.Cu" signal "GND5")
		(28 "In13.Cu" signal "IN5")
		(30 "In14.Cu" signal "GND6")
		(32 "In15.Cu" signal "IN6")
		(34 "In16.Cu" signal "GND7")
		(2 "B.Cu" signal "BOTTOM")
		(9 "F.Adhes" user "F.Adhesive")
		(11 "B.Adhes" user "B.Adhesive")
		(13 "F.Paste" user "Package Geometry/Pastemask Top")
		(15 "B.Paste" user "Package Geometry/Pastemask Bottom")
		(5 "F.SilkS" user "Ref Des/Silkscreen Top")
		(7 "B.SilkS" user "Ref Des/Silkscreen Bottom")
		(1 "F.Mask" user "Board Geometry/Soldermask Top")
		(3 "B.Mask" user "Board Geometry/Soldermask Bottom")
		(17 "Dwgs.User" user "User.Drawings")
		(19 "Cmts.User" user "User.Comments")
		(21 "Eco1.User" user "User.Eco1")
		(23 "Eco2.User" user "User.Eco2")
		(25 "Edge.Cuts" user "Board Geometry/Outline")
		(27 "Margin" user)
		(31 "F.CrtYd" user "Package Geometry/Place Bound Top")
		(29 "B.CrtYd" user "Package Geometry/Place Bound Bottom")
		(35 "F.Fab" user "Ref Des/Assembly Top")
		(33 "B.Fab" user "Ref Des/Assembly Bottom")
	)
	(footprint ""
		(layer "B.Cu")
		(at 169.389806 -9.458198 -90)
		(property "Reference" "C2077"
			(at 0 0 90)
			(layer "B.SilkS")
			(hide yes)
			(effects
				(font
					(size 1.27 1.27)
				)
				(justify mirror)
			)
		)
		(property "Value" ""
			(at 0 0 90)
			(layer "B.Fab")
			(effects
				(font
					(size 1.27 1.27)
				)
				(justify mirror)
			)
		)
		(duplicate_pad_numbers_are_jumpers no)
		(fp_line
			(start -0.299974 0.150114)
			(end 0.299974 0.150114)
			(stroke
				(width 0.1)
				(type default)
			)
			(layer "B.Fab")
		)
		(fp_line
			(start 0.299974 0.150114)
			(end 0.299974 -0.150114)
			(stroke
				(width 0.1)
				(type default)
			)
			(layer "B.Fab")
		)
		(fp_line
			(start -0.299974 -0.150114)
			(end -0.299974 0.150114)
			(stroke
				(width 0.1)
				(type default)
			)
			(layer "B.Fab")
		)
		(fp_line
			(start 0.299974 -0.150114)
			(end -0.299974 -0.150114)
			(stroke
				(width 0.1)
				(type default)
			)
			(layer "B.Fab")
		)
		(pad "1" smd rect
			(at 0.2667 0 90)
			(size 0.3048 0.381)
			(layers "B.Cu" "B.Mask" "B.Paste")
			(net "P3E_PCH_BMC_TX_DP")
		)
		(pad "2" smd rect
			(at -0.2667 0 90)
			(size 0.3048 0.381)
			(layers "B.Cu" "B.Mask" "B.Paste")
			(net "P3E_PCH_BMC_TX_C_DP")
		)
		(zone
			(layer "In16.Cu")
			(hatch none 0.5)
			(connect_pads
				(clearance 0)
			)
			(min_thickness 0.25)
			(keepout
				(tracks not_allowed)
				(vias allowed)
				(pads allowed)
				(copperpour not_allowed)
				(footprints allowed)
			)
			(placement
				(enabled no)
				(sheetname "")
			)
			(fill
				(thermal_gap 0.5)
				(thermal_bridge_width 0.5)
				(island_removal_mode 0)
			)
			(polygon
				(pts
					(xy 169.148506 -9.521698) (xy 169.631106 -9.521698) (xy 169.631106 -9.928098) (xy 169.148506 -9.928098)
				)
			)
		)
		(zone
			(layer "In16.Cu")
			(hatch none 0.5)
			(connect_pads
				(clearance 0)
			)
			(min_thickness 0.25)
			(keepout
				(tracks not_allowed)
				(vias allowed)
				(pads allowed)
				(copperpour not_allowed)
				(footprints allowed)
			)
			(placement
				(enabled no)
				(sheetname "")
			)
			(fill
				(thermal_gap 0.5)
				(thermal_bridge_width 0.5)
				(island_removal_mode 0)
			)
			(polygon
				(pts
					(xy 169.148506 -8.988298) (xy 169.631106 -8.988298) (xy 169.631106 -9.394698) (xy 169.148506 -9.394698)
				)
			)
		)
	)
	(footprint ""
		(layer "B.Cu")
		(at 339.44306 -66.425064 90)
		(property "Reference" "C168"
			(at 0 0 90)
			(layer "B.SilkS")
			(hide yes)
			(effects
				(font
					(size 1.27 1.27)
				)
				(justify mirror)
			)
		)
		(property "Value" ""
			(at 0 0 90)
			(layer "B.Fab")
			(effects
				(font
					(size 1.27 1.27)
				)
				(justify mirror)
			)
		)
		(duplicate_pad_numbers_are_jumpers no)
		(fp_line
			(start 0.299974 -0.150114)
			(end -0.299974 -0.150114)
			(stroke
				(width 0.1)
				(type default)
			)
			(layer "B.Fab")
		)
		(fp_line
			(start -0.299974 -0.150114)
			(end -0.299974 0.150114)
			(stroke
				(width 0.1)
				(type default)
			)
			(layer "B.Fab")
		)
		(fp_line
			(start 0.299974 0.150114)
			(end 0.299974 -0.150114)
			(stroke
				(width 0.1)
				(type default)
			)
			(layer "B.Fab")
		)
		(fp_line
			(start -0.299974 0.150114)
			(end 0.299974 0.150114)
			(stroke
				(width 0.1)
				(type default)
			)
			(layer "B.Fab")
		)
		(pad "1" smd rect
			(at 0.2667 0 270)
			(size 0.3048 0.381)
			(layers "B.Cu" "B.Mask" "B.Paste")
			(net "DMI_CPU0_PCH_RX_C_DP<1>")
		)
		(pad "2" smd rect
			(at -0.2667 0 270)
			(size 0.3048 0.381)
			(layers "B.Cu" "B.Mask" "B.Paste")
			(net "DMI_CPU0_PCH_RX_DP<1>")
		)
	)
	(footprint ""
		(layer "B.Cu")
		(at 185.240422 -13.60043 -90)
		(property "Reference" "R598"
			(at 0 0 90)
			(layer "B.SilkS")
			(hide yes)
			(effects
				(font
					(size 1.27 1.27)
				)
				(justify mirror)
			)
		)
		(property "Value" ""
			(at 0 0 90)
			(layer "B.Fab")
			(effects
				(font
					(size 1.27 1.27)
				)
				(justify mirror)
			)
		)
		(duplicate_pad_numbers_are_jumpers no)
		(fp_line
			(start -0.7874 0.4064)
			(end 0.7874 0.4064)
			(stroke
				(width 0.1524)
				(type default)
			)
			(layer "B.SilkS")
		)
		(fp_line
			(start 0.7874 0.4064)
			(end 0.7874 -0.4064)
			(stroke
				(width 0.1524)
				(type default)
			)
			(layer "B.SilkS")
		)
		(fp_line
			(start -0.7874 -0.4064)
			(end -0.7874 0.4064)
			(stroke
				(width 0.1524)
				(type default)
			)
			(layer "B.SilkS")
		)
		(fp_line
			(start 0.7874 -0.4064)
			(end -0.7874 -0.4064)
			(stroke
				(width 0.1524)
				(type default)
			)
			(layer "B.SilkS")
		)
		(fp_line
			(start -0.67945 0.3048)
			(end -0.120396 0.3048)
			(stroke
				(width 0.1)
				(type default)
			)
			(layer "B.Fab")
		)
		(fp_line
			(start -0.120396 0.3048)
			(end -0.120396 0.2794)
			(stroke
				(width 0.1)
				(type default)
			)
			(layer "B.Fab")
		)
		(fp_line
			(start 0.12065 0.3048)
			(end 0.67945 0.3048)
			(stroke
				(width 0.1)
				(type default)
			)
			(layer "B.Fab")
		)
		(fp_line
			(start 0.67945 0.3048)
			(end 0.67945 -0.305054)
			(stroke
				(width 0.1)
				(type default)
			)
			(layer "B.Fab")
		)
		(fp_line
			(start -0.120396 0.2794)
			(end 0.12065 0.2794)
			(stroke
				(width 0.1)
				(type default)
			)
			(layer "B.Fab")
		)
		(fp_line
			(start 0.12065 0.2794)
			(end 0.12065 0.3048)
			(stroke
				(width 0.1)
				(type default)
			)
			(layer "B.Fab")
		)
		(fp_line
			(start -0.12065 -0.2794)
			(end -0.12065 -0.3048)
			(stroke
				(width 0.1)
				(type default)
			)
			(layer "B.Fab")
		)
		(fp_line
			(start 0.12065 -0.2794)
			(end -0.12065 -0.2794)
			(stroke
				(width 0.1)
				(type default)
			)
			(layer "B.Fab")
		)
		(fp_line
			(start -0.67945 -0.3048)
			(end -0.67945 0.3048)
			(stroke
				(width 0.1)
				(type default)
			)
			(layer "B.Fab")
		)
		(fp_line
			(start -0.12065 -0.3048)
			(end -0.67945 -0.3048)
			(stroke
				(width 0.1)
				(type default)
			)
			(layer "B.Fab")
		)
		(fp_line
			(start 0.12065 -0.305054)
			(end 0.12065 -0.2794)
			(stroke
				(width 0.1)
				(type default)
			)
			(layer "B.Fab")
		)
		(fp_line
			(start 0.67945 -0.305054)
			(end 0.12065 -0.305054)
			(stroke
				(width 0.1)
				(type default)
			)
			(layer "B.Fab")
		)
		(pad "1" smd circle
			(at 0.40005 0 90)
			(size 0 0)
			(layers "B.Cu" "B.Mask" "B.Paste")
			(net "I3C_SPD_DDRABCD_CPU1_BMC_R_SDA")
		)
		(pad "2" smd circle
			(at -0.40005 0 90)
			(size 0 0)
			(layers "B.Cu" "B.Mask" "B.Paste")
			(net "I3C_SPD_DDRABCD_CPU1_BMC_SDA")
		)
	)
)
